# ZAIUS-MB-PVT-X04-BOM_X31_20180131_Final.xls.xlsx — DEPOP (bom)
| FOXCONN TECHNOLOGY GROUP |  |  |  |  |  |  |  |  |  |  |  |  |
| BILL OF MATERIAL |  |  |  |  |  |  |  |  |  |  |  |  |
| REV OF  BOM | X31 | CUSTOMER | <name> |  | CUSTOMER P/N |  | PRODUCT CODE |  | PWA  REV | X04 | DATE | 43131 |
| Sourcing (Single/Sole/Multi) | Critical Commodity (Y or N) | Component Class (1, 2, other) | Customer PSL (Y or N) | Item Number | Foxconn P/N | Customer P/N | Part Description | Manufacturer  Full Name | Manufacturer  Part Number | Qty | RoHS Status | Location |
|  | Y | 2 | Y(3) | 1 | 62010FF00-015-G |  | CAP,47pF,+/-5%,NPO(C0G),50V,G,SMD0402 | MURATA ELEC. NORTH AMERICA | GRM1555C1H470J | 38 | Y | C1,C2,C3,C4,C7,C8,C16,C17,C18,C19,C20,C21,C22,C23,C24,C25,C26,C27,C28,C29,C30,C31,C32,C726,C727,C728,C729,C739,C740,C741,C742,C743,C744,C745,C746,C747,C748,C2180 |
|  | ND | ND | Y(3) | 2 | 620103700-015-G |  | CAP,100nF,+/-10%,X7R,10V,G,SMD0402 | MURATA ELEC. NORTH AMERICA | GRM155R71A104K | 8 | Y | C37,C204,C205,C753,C1497,C1498,C2126,C2127 |
|  | Y | ND | Y(1) | 3 | 62012WD00-015-G |  | CAP,4.7uF,+/-20%,X6S,6.3V,G,SMD0402 | MURATA ELEC. NORTH AMERICA | GRM155C80J475MEAAD | 2 |  | C60,C757 |
|  | Y | 2 | Y(3) | 4 | 62011DF01-015-G |  | CAP,220nF,+/-10%,X7R,16V,G,SMD0402 | MURATA ELEC. NORTH AMERICA | GRM155R71C224K | 8 | N | C80,C83,C138,C794,C795,C814,C897,C904 |
|  | Y | 2 | Y(3) | 5 | 620107G00-015-G |  | CAP,47nF,+/-10%,X7R,16V,G,SMD0402 | MURATA ELEC. NORTH AMERICA | GRM155R71C473K | 3 | N | C184,C231,C232 |
|  | ND | ND | N | 6 | 62012NU00-015-G |  | CAP,1uF,+/-10%,X7R,6.3V,G,SMD0402 | MURATA ELEC. NORTH AMERICA | GRM155R70J105KA12D | 1 | N | C202 |
|  | ND |  | Y(1) | 7 | 62012PS00-015-G |  | CAP,10uF,+/-20%,X6S,4V,G,SMD0402 | MURATA ELEC. NORTH AMERICA | GRM155C80G106M | 10 |  | PBFC61,PBEC61,PAFC61,PAEC61,PBMC62,PAMC62,PBAC126,PAAC126,C264,C2171 |
|  | Y | 2 | Y(3) | 8 | 620101T02-015-G |  | CAP,100nF,+/-10%,X7R,16V,G,SMD0402 | MURATA ELEC. NORTH AMERICA | GRM155R71C104K | 60 | Y | PSPC13,PIPC13,PFPC13,PEPC13,C1403,C1404,C1405,C1406,C1407,C1408,C1409,C1410,C1411,C1412,C1413,C1414,C1415,C1416,C1417,C1418,C1419,C1422,C1423,C1425,C1426,C1428,C1429,C1430,C1431,C1432,C1433,C1434,C1435,C1436,C1437,C1438,C1441,C1442,C1443,C1444,C1445,C1446,C1449,C1450,C1452,C1453,C1454,C1457,C1460,C1461,C1462,C1465,C1467,C1469,C1471,C1472,C1552,C1561,C1562,C2163 |
|  | ND | ND | Y(3) | 9 | 62010MU00-015-G |  | CAP,20pF,+/-5%,NPO(C0G),50V,G,SMD0402 | MURATA ELEC. NORTH AMERICA | GRM1555C1H200J | 2 | N | C1420,C1421 |
|  | ND | ND | Y(1) | 10 | 620109S00-015-G |  | CAP,4.7uF,+/-10%,X7R,10V,G,SMD0805 | MURATA ELEC. NORTH AMERICA | GRM21BR71A475K | 9 | N | C1424,C1427,C1451,C1455,C1459,C1464,C1466,C1468,C1470 |
|  | Y | 2 | Y(1) | 11 | 620109200-015-G |  | CAP,10uF,+/-10%,X7R,6.3V,G,SMD0805 | MURATA ELEC. NORTH AMERICA | GRM21BR70J106K | 5 | N | C1439,C1440,C1447,C1448,C1456 |
|  | ND |  | Y(1) | 12 | 620115801-015-G |  | CAP,22uF,+/-10%,X7R,10V,G,SMD1206 | MURATA ELEC. NORTH AMERICA | GRM31CR71A226KE15L | 2 |  | C1458,C1463 |
|  | Y | 2 | ND | 13 | 620108000-015-G |  | CAP,100pF,+/-5%,NPO(C0G),50V,G,SMD0402 | MURATA ELEC. NORTH AMERICA | GRM1555C1H101J | 7 | Y | C1473,C1474,C1554,C1559,C1565,C1567,C2136 |
|  | Y | ND | Y(3) | 14 | 62011U701-015-G |  | CAP,10nF,+/-10%,X7R,6.3V,G,SMD0402 | MURATA ELEC. NORTH AMERICA | GRM155R70J103K | 1 |  | C1511 |
|  | ND | ND | Y(3) | 15 | 62010K200-015-G |  | CAP,12pF,+/-5%,NPO(C0G),50V,G,SMD0402 | MURATA ELEC. NORTH AMERICA | GRM1555C1H120J | 6 | N | C1546,C1547,C1548,C1549,C1550,C1551 |
|  | ND | ND | Y(3) | 16 | 62010BJ00-015-G |  | CAP,56pF,+/-5%,NPO(C0G),50V,G,SMD0402 | MURATA ELEC. NORTH AMERICA | GRM1555C1H560J | 2 | N | C1553,C1558 |
|  | Y | 2 | Y(3) | 17 | 62010GW00-015-G |  | CAP,10pF,+/-5%,NPO,50V,G,SMD0402 | MURATA ELEC. NORTH AMERICA | GRM1555C1H100J | 22 | N | PBMC8,PBFC8,PBEC8,PBAC8,PAMC8,PAFC8,PAEC8,PAAC8,PBMC9,PBFC9,PBEC9,PBAC9,PAMC9,PAFC9,PAEC9,PAAC9,C1555,C1556,C1557,C1560,C1564,C1566 |
|  | Y | 2 | Y(1) | 18 | 62011D900-015-G |  | CAP,22uF,+/-10%,X7R,6.3V,G,SMD1206 | MURATA ELEC. NORTH AMERICA | GRM31CR70J226K | 1 | N | C1563 |
|  | ND | ND | Y(3) | 19 | 620108100-015-G |  | CAP,15pF,+/-5%,NPO(C0G),50V,G,SMD0402 | MURATA ELEC. NORTH AMERICA | GRM1555C1H150J | 2 | N | C2008,C2010 |
|  | ND | ND | Y(3) | 20 | 62010QB00-015-G |  | CAP,10nF,+/-10%,X7R,50V,G,SMD0402 | MURATA ELEC. NORTH AMERICA | GRM155R71H103K | 11 | N | PSRC1,PSTC9,PSLC9,PSFC9,PSEC9,PSDC9,PQPC9,PFRC9,PEEC9,PEDC9,C2071 |
|  | ND | ND | Y(1) | 21 | 62012A400-015-G |  | CAP,100nF,+/-10%,X7R,25V,G,SMD0402 | MURATA ELEC. NORTH AMERICA | GRM155R71E104KE14D | 1 | N | C2097 |
|  | ND |  | Y(3) | 22 | 620106200-015-G |  | CAP,10nF,+/-10%,X7R,16V,G,SMD0402 | MURATA ELEC. NORTH AMERICA | GRM155R71C103KA01D | 1 | Y | C2098 |
|  | ND | ND | Y(1) | 23 | 62010P501-015-G |  | CAP,1nF,+/-10%,X7R,16V,G,SMD0402 | MURATA ELEC. NORTH AMERICA | GRM155R71C102KA01D | 2 | N | C2111,C2187 |
|  | ND | ND | Y(3) | 24 | 620108B00-015-G |  | CAP,120pF,+/-5%,NPO(C0G),50V,G,SMD0402 | MURATA ELEC. NORTH AMERICA | GRM1555C1H121J | 4 | N | C2182,C2183,C2184,C2185 |
|  | Y | 1 | Y(3) | 25 | 520305M00-223-G |  | DIODE,Schottky Rectifier,MBRS340T3G,40V,3A,G,SMC,SMD | ON SEMICONDUCTOR CORP | MBRS340T3G | 8 | N | D1,D2,D3,D4,D5,D6,D7,D51 |
|  |  |  | Y(4) | 26 | 520300500-223-G |  | DIODE,Schottky,BAT54SLT1G,30V,0.2A,G,SOT23-3,SMD | ON SEMICONDUCTOR CORP | BAT54SLT1G | 7 | N | D9,D10,D11,D12,D13,D16,D18 |
|  | ND | ND | Y(4) | 27 | 520305J00-223-G |  | DIODE,Schottky,MBR130LSFT1G,30V,1A,G,SOD123FL-2,SMD | ON SEMICONDUCTOR CORP | MBR130LSFT1G | 1 | Y | D14 |
|  | Y | 1 | Y(3) | 28 | 520306Y00-223-G |  | DIODE,Schottky Rectifier,MBR0530T1G,30V,0.5A,G,SOD123-2,SMD | ON SEMICONDUCTOR CORP | MBR0530T1G | 2 | Y | D15,D17 |
|  | ND |  | N | 29 | 520306F00-223-G |  | DIODE,Schottky,NSR0320MW2T1G,20V,1A,G,SOD323-2,SMD | ON SEMICONDUCTOR CORP | NSR0320MW2T1G | 1 | N | D52 |
|  | N | other | Y(3) | 30 | 730200800-101-G |  | Polyswitch,PTC,6V,1.5A,G,SMD1206 | BOURNS INC | MF-NSMF150-2 | 1 |  | FS1 |
|  | N | 1 | N | 31 | 52111AE00-289-G |  | LED,Ora,LTST-C281KFKT-5A,5V,30mA,G,SMD0402 | LITE-ON TECHNOLOGY CORPORATION | LTST-C281KFKT-5A | 1 |  | LED4 |
|  | N | 1 | N | 32 | 52111J100-289-G |  | LED,Gre,LTST-C281KGKT-5A,2.3V,30mA,G,SMD0402 | LITE-ON TECHNOLOGY CORPORATION | LTST-C281KGKT-5A | 1 |  | LED5 |
|  | ND | ND | Y(1) | 33 | 21040HY00-283-G |  | IC,BROADCOM,BCM5719A1KFBG,A1,G,FBGA-256,SMD | BROADCOM SINGAPORE PTE LTD. | BCM5719A1KFBG | 1 |  | LOM1 |
|  | Y | Other | Y(2) | 34 | 720108301-015-G |  | FB,600 Ohm@100MHz,+/-25%,500mA,350mOhm,G,SMD0603 | MURATA ELEC. NORTH AMERICA | BLM18EG601SN1D | 10 | N | L2,L3,L4,L5,L6,L8,L9,L10,L11,L12 |
|  | ND | ND | N | 35 | 630332000-053-G |  | IND,3.3uH@100KHz,+/-20%,2.57A,26mOhm,SHLD,G,SMD | TOKO INC. | #A916CY-3R3M=P3 | 1 |  | L7 |
|  | ND | ND | N | 36 | 630100U00-016-G |  | IND,68nH@50MHz,+/-20%,50mA,300mOhm,G,SMD0603 | TDK ELECTRONICS EUROPE GMBH | MLF1608D68NMT | 3 | N | L18,L19,L20 |
|  | ND | ND | Y(2) | 37 | 720107U00-015-G |  | FB,220 Ohm@100MHz,+/-25%,2A,50mOhm,G,SMD0805 | MURATA ELEC. NORTH AMERICA | BLM21PG221SN1D | 1 | N | L21 |
|  | N |  | Y(1) | 38 | 62011J601-015-G |  | CAP,2.2uF,+/-10%,X7R,100V,G,SMD1210 | MURATA ELEC. NORTH AMERICA | GRM32ER72A225K | 8 |  | PBMC20,PBFC20,PAMC20,PAEC20,PBEC21,PBAC21,PAFC21,PAAC21 |
|  | N | ND | Y(3) | 39 | 62012GY00-015-G |  | CAP,100nF,+/-20%,X7R,25V,G,SMD0402 | MURATA ELEC. NORTH AMERICA | GRM155R71E104M | 16 |  | PBMC23,PBFC23,PBEC23,PAMC23,PAFC23,PAEC23,PBMC24,PBFC24,PBEC24,PBAC24,PAMC24,PAFC24,PAEC24,PAAC24,PBAC25,PAAC25 |
|  | ND | ND | Y(1) | 40 | 62011DA00-015-G |  | CAP,1uF,+/-10%,X7R,100V,G,SMD1206 | MURATA ELEC. NORTH AMERICA | GRM31CR72A105K | 14 | Y | PBFC26,PBEC26,PAFC26,PAEC26,PBMC28,PBAC28,PAMC28,PAAC28,PBAC79,PAAC79,PBAC80,PAAC80,PBAC112,PAAC112 |
|  | ND | ND | Y(3) | 41 | 62010VD00-015-G |  | CAP,100nF,+/-10%,X7R,100V,G,SMD0603 | MURATA ELEC. NORTH AMERICA | GRM188R72A104K | 14 |  | PBFC401,PBEC401,PBAC401,PAMC401,PAFC401,PAEC401,PAAC401,PBFC402,PBEC402,PBAC402,PAMC402,PAFC402,PAEC402,PAAC402 |
|  | Y |  | Y(1) | 42 | 62012RJ00-015-G |  | CAP,4.7uF,+/-10%,X6S,16V,G,SMD0603 | MURATA ELEC. NORTH AMERICA | GRM188C81C475K | 2 |  | PBAC451,PAAC451 |
|  | ND |  | N | 43 | 52030W700-237-G |  | DIODE,Schottky,BAT54WT-7,30V,100mA,G,SOD523-2,SMD | DIODES INEORPORATION | BAT54WT-7 | 8 |  | PBMD2,PBFD2,PBED2,PBAD2,PAMD2,PAFD2,PAED2,PAAD2 |
|  | ND |  | N | 44 | 52030TQ00-237-G |  | Diode,Schottky,BAS40-06-7-F,40V,200mA,G,SOT-23-3,SMD | DIODES INCORPORATION | BAS40-06-7-F | 2 | N | PBAD4,PAAD4 |
|  | N |  | N | 45 | 63035NQ00-029-G |  | IND,0.1uH@100KHz,+/-20%,11.5A,6mOhm,SHLD,G,SMD | VISHAY ENTER TECHNO LOGY.INC | IHLP1616ABERR10M01 | 2 |  | PBAL4,PAAL4 |
|  | N | ND | Y(4) | 46 | 610107A00-017-G |  | RES,0 Ohm,+/-5%,1/16W,G,SMD0402 | KOA SPEER ELECTRONICS, INC. | RK73Z1ETTP | 310 | N | PSUR3,PSRR5,PBFR5,PBER5,PAFR5,PAER5,PBFR6,PBER6,PBAR6,PAFR6,PAER6,PBMR7,PBAR7,PAFR7,PAAR7,PSTR8,PSER8,PBFR8,PBER8,PAAR8,PAER9,PBAR10,PAMR10,PHAR11,PBFR11,PAAR11,PBMR12,PBER12,PAER12,PSTR13,PSLR13,PSFR13,PSER13,PSDR13,PQPR13,PFRR13,PEER13,PEDR13,PBAR13,PAFR13,PAER13,PAMR15,PHAR16,PBFR16,PBER16,PAFR16,PAAR16,PSPR17,PIPR17,PHAR17,PFPR17,PEPR17,PHAR18,PBMR19,PBFR19,PBER19,PBAR19,PAMR19,PAFR19,PAER19,PAAR19,PBMR20,PBFR20,PBER20,PBAR20,PAMR20,PAFR20,PAER20,PAAR20,PBMR23,PBFR23,PBER23,PBAR23,PAMR23,PAFR23,PAER23,PAAR23,PSRR24,PHAR26,PHAR27,PBNR28,PANR28,PBMR29,PBFR29,PBER29,PBAR29,PAMR29,PAFR29,PAER29,PAAR29,PBMR31,PBFR31,PBER31,PBAR31,PAMR31,PAFR31,PAER31,PAAR31,PBMR37,PBFR37,PBER37,PBAR37,PAMR37,PAFR37,PAER37,PAAR37,PBMR73,PAMR73,PBER76,PBAR76,PAFR76,PAER76,PAAR76,PBFR77,PBMR80,PAMR80,PBAR82,PAFR82,PAAR82,PBMR83,PBFR83,PBAR83,PAMR83,PAAR83,PBMR84,PAMR84,PBER86,PAFR86,PAER86,PBFR87,PBAR87,PAAR87,PBER88,PBAR88,PAFR88,PAER88,PAAR88,PBFR89,PBAR99,PAAR99,PBMR101,PAMR101,PBER103,PAFR103,PAER103,PBFR104,PBMR105,PAMR105,PBMR106,PAMR106,PBER107,PBAR107,PAFR107,PAER107,PAAR107,PBMR108,PBFR108,PBER108,PAMR108,PAFR108,PAER108,PBFR109,PBER110,PAFR110,PAER110,PBFR111,PBAR111,PAAR111,PBMR112,PBAR112,PAMR112,PAAR112,PBMR114,PBER114,PBAR114,PAMR114,PAFR114,PAER114,PAAR114,PBFR115,PBER116,PAFR116,PAER116,PBFR117,PBAR118,PAAR118,PBMR119,PAMR119,PBMR120,PBAR120,PAMR120,PAAR120,PBER121,PAFR121,PAER121,PBFR122,PBER122,PAFR122,PAER122,PBFR123,PBAR125,PAAR125,PBAR126,PAAR126,PBFR304,PBER304,PAFR304,PAER304,PBFR308,PAFR308,PAER308,PBFR309,PBER309,PAFR309,PAER309,PBER310,PBMR311,PBFR311,PBAR311,PAMR311,PAFR311,PAER311,PAAR311,PBMR312,PBER312,PBAR312,PAMR312,PAAR312,PBAR313,PAAR313,PBMR450,PBFR450,PBER450,PBAR450,PAMR450,PAFR450,PAER450,PAAR450,PAAR451,PBAR452,PAAR452,PBAR454,PBMR610,PBAR610,PAMR610,PAAR610,PBAR611,PAAR611,PBAR612,PAAR612,PAFR635,R653,R654,R655,R656,R659,PBFR660,PBER660,R661,R662,R670,R671,R674,R677,PAER685,R717,R722,R723,R724,R726,R728,R752,R768,R803,R819,R821,R948,R1071,R1087,R1101,R1103,R1107,R1142,R1144,R1230,R1250,R1287,R1445,R1452,R1453,R1454,R1455,R1456,R1457,R1458,R1459,R1479,R1486,R1489,R1529,R1530,R1556,R1557,R1787,R1788,PSRR3004,PEPR3008,PIPR3009,PFPR3009,PSPR3014 |
|  | N | ND | Y(4) | 47 | 61010G500-017-G |  | RES,10KOhm,+/-1%,1/16W,G,SMD0402 | KOA SPEER ELECTRONICS, INC. | RK73H1ETTP1002F | 55 | N | PHAR3,PBMR51,PBFR51,PBER51,PBAR51,PAMR51,PAFR51,PAER51,PAAR51,PBMR52,PBFR52,PBER52,PBAR52,PAMR52,PAFR52,PAER52,PAAR52,PBMR53,PBFR53,PBER53,PBAR53,PAMR53,PAFR53,PAER53,PAAR53,PBMR71,PAMR71,PBMR72,PAMR72,PBER73,PBAR73,PAFR73,PAER73,PAAR73,PBFR74,PBER75,PBAR75,PAFR75,PAER75,PAAR75,PBFR76,R719,R903,R904,R905,R906,R907,R908,R920,R953,R1013,R1014,R1415,R1790,PSRR3007 |
|  | N | Other | Y(4) | 48 | 610130Y00-017-G |  | RES,1 Ohm,+/-1%,1/3W,G,SMD1206 | KOA SPEER ELECTRONICS, INC. | SR732BTTD1R00F | 10 |  | PBMR60,PBAR60,PAMR60,PAAR60,PBER63,PAFR63,PAER63,PBFR64,PBAR100,PAAR100 |
|  | N | ND | Y(4) | 49 | 610108300-017-G |  | RES,0 Ohm,+/-5%,1/10W,G,SMD0603 | KOA SPEER ELECTRONICS, INC. | RK73Z1JTTD | 19 | N | PBNR1,PANR1,PBMR67,PAMR69,PBAR74,PAAR74,PBER80,PAFR80,PAER80,PBFR81,PAER123,PBFR520,PBER520,PAFR520,PBMR609,PBAR609,PAMR609,PAAR609,R1845 |
|  | N | ND | Y(4) | 50 | 61010L300-017-G |  | RES,1KOhm,+/-1%,1/16W,G,SMD0402 | KOA SPEER ELECTRONICS, INC. | RK73H1ETTP1001F | 16 | N | R14,R15,PBMR310,PBAR310,PAMR310,PAAR310,R377,R378,R657,R660,R678,R679,R1016,R1022,R1444,R1499 |
|  | ND | ND | Y(4) | 51 | 61010L100-017-G |  | RES,100KOhm,+/-1%,1/16W,G,SMD0402 | KOA SPEER ELECTRONICS, INC. | RK73H1ETTP1003F | 8 | N | PBFR517,PBER517,PAFR517,PAER518,PBMR602,PBAR602,PAMR602,PAAR602 |
|  | N |  | N | 52 | 880302200-53N-G |  | Converter,input 0V~60V,185W,G,VTM48MP012T130AA0 | Vicor Corporation | VTM48MP012T130AA0 | 2 |  | PBAU5,PAAU5 |
|  | N |  | Y(3) | 53 | 62120ER01-024-G |  | ECAP,SPEA,470uF,+/-20%,2.5V,105C,G,SMD2816,ESR<=3mOhm | PANASONIC INDUSTRIAL CO.,LTD. | EEFGX0E471R | 8 |  | PBECE7,PAFCE7,PAECE7,PBFCE8,PBECE8,PAFCE8,PAECE8,PBFCE9 |
|  | ND | ND | Y(1) | 54 | 62010L800-015-G |  | CAP,1nF,+/-5%,NPO(C0G),50V,G,SMD0402 | MURATA ELEC. NORTH AMERICA | GRM1555C1H102J | 5 | N | PBFC5,PBEC5,PAFC5,PAEC5,PSRC8 |
|  | ND | ND | Y(4) | 55 | 61010PS00-017-G |  | RES,200KOhm,+/-1%,1/16W,G,SMD0402 | KOA SPEER ELECTRONICS, INC. | RK73H1ETTP2003F | 4 | N | PBFR9,PBER10,PAFR12,PAER14 |
|  | ND | ND | Y(4) | 56 | 610114S00-017-G |  | RES,4.99KOhm,+/-1%,1/16W,G,SMD0402 | KOA SPEER ELECTRONICS, INC. | RK73H1ETTP4991F | 4 | N | PBFR39,PBER39,PAFR39,PAER39 |
|  | ND |  | Y(1) | 57 | 62012UU00-015-G |  | CAP,100uF,+/-20%,X6S,4V,G,SMD0805 | MURATA ELEC. NORTH AMERICA | GRM21BC80G107ME15L | 2 |  | PBNC24,PANC24 |
|  | ND | ND | Y(4) | 58 | 61010LA00-017-G |  | RES,4.7KOhm,+/-1%,1/16W,G,SMD0402 | KOA SPEER ELECTRONICS, INC. | RK73H1ETTP4701F | 51 | N | PSPR1,PIPR1,PFPR1,PEPR1,PBNR2,PANR2,PSRR6,PBNR9,PANR9,PSPR16,PIPR16,PFPR16,PEPR16,R352,R354,R358,R360,R663,R668,R669,R681,R682,R683,R684,R685,R686,R687,R708,R709,R710,R731,R732,R765,R897,R939,R1001,R1017,R1023,R1119,R1126,R1153,R1240,R1294,R1526,R1533,R1548,R1786,PSPR3005,PIPR3005,PFPR3005,PEPR3005 |
|  | ND |  | N | 59 | 61011G200-017-G |  | RES,12.4KOhm,+/-1%,1/16W,G,SMD0402 | KOA SPEER ELECTRONICS, INC. | RK73H1ETTP1242F | 2 | N | PBNR8,PANR8 |
|  | N | ND | Y(4) | 60 | 610114A00-017-G |  | RES,24.9KOhm,+/-1%,1/16W,G,SMD0402 | KOA SPEER ELECTRONICS, INC. | RK73H1ETTP2492F | 2 | N | PBNR19,PANR19 |
|  | ND |  | Y(4) | 61 | 61011CL00-017-G |  | RES,66.5KOhm,+/-1%,1/16W,G,SMD0402 | KOA SPEER ELECTRONICS, INC. | RK73H1ETTP6652F | 2 | N | PBNR25,PANR25 |
|  | ND | ND | N | 62 | 62010HR00-015-G |  | CAP,100nF,+/-10%,X7R,50V,G,SMD0603 | MURATA ELEC. NORTH AMERICA | GRM188R71H104K | 11 | N | PUAC9,PSIC9,PSAC9,PRAC9,PQAC9,PPAC9,PIAC9,PFAC9,PETC9,PERC9,PEAC9 |
|  | Y | 2 | Y(4) | 63 | 620103K00-015-G |  | CAP,1nF,+/-10%,X7R,50V,G,SMD0402 | MURATA ELEC. NORTH AMERICA | GRM155R71H102K | 11 | N | PUAC17,PSIC17,PSAC17,PRAC17,PQAC17,PPAC17,PIAC17,PFAC17,PETC17,PERC17,PEAC17 |
|  | Y | 2 | Y(4) | 64 | 620105U00-015-G |  | CAP,220pF,+/-10%,X7R,50V,G,SMD0402 | MURATA ELEC. NORTH AMERICA | GRM155R71H221K | 9 | N | PSTC13,PSLC13,PSFC13,PSEC13,PSDC13,PQPC13,PFRC13,PEEC13,PEDC13 |
|  | N | ND | Y(4) | 65 | 610112M00-017-G |  | RES,13KOhm,+/-1%,1/16W,G,SMD0402 | KOA SPEER ELECTRONICS, INC. | RK73H1ETTP1302F | 8 | N | PSTR1,PSLR1,PSFR1,PSER1,PSDR1,PQPR1,PEER1,PEDR1 |
|  | N | ND | Y(4) | 66 | 610114H00-017-G |  | RES,20KOhm,+/-1%,1/16W,G,SMD0402 | KOA SPEER ELECTRONICS, INC. | RK73H1ETTP2002F | 12 | N | PSTR3,PSLR3,PSFR3,PSER3,PSDR3,PQPR3,PEER3,PEDR3,R1757,R1758,R1759,R1760 |
|  | ND | ND | Y(4) | 67 | 61011HA00-017-G |  | RES,1 Ohm,+/-1%,1/16W,G,SMD0402 | KOA SPEER ELECTRONICS, INC. | RK73H1ETTP1R00F | 10 | N | PSTR14,PSLR14,PSFR14,PSER14,PSDR14,PQPR14,PFRR14,PEER14,PEDR14,PSRR19 |
|  | ND | ND | Y(4) | 68 | 61011H300-017-G |  | RES,316 Ohm,+/-1%,1/16W,G,SMD0402 | KOA SPEER ELECTRONICS, INC. | RK73H1ETTP3160F | 8 | N | PSPR18,PIPR18,PFPR18,PEPR18,PIPR3008,PFPR3008,PEPR3009,PSPR3015 |
|  | N |  | Y(5) | 69 | 61100LR00-017-G |  | RES,100 Ohm,+/-1%,1/16W,G,SMD0402 | KOA SPEER ELECTRONICS, INC. | RN731ETTP1000F50 | 6 |  | PSPR19,PIPR19,PFPR19,PEPR19,R1485,R1785 |
|  | ND | ND | Y(5) | 70 | 61100BP00-017-G |  | RES,3.09KOhm,+/-0.1%,1/16W,G,SMD0402 | KOA SPEER ELECTRONICS, INC. | RN731ETTP3091B25 | 4 | Y | PSPR3006,PIPR3006,PFPR3006,PEPR3006 |
|  | ND |  | Y(5) | 71 | 61100N100-017-G |  | RES,2.37KOhm,+/-0.1%,1/16W,G,SMD0402 | KOA SPEER ELECTRONICS, INC. | RN731ETTP2371B25 | 1 | Y | PSRR3 |
|  | ND |  | Y(5) | 72 | 61100PK00-017-G |  | RES,10.7KOhm,+/-0.1%,1/16W,G,SMD0402 | KOA SPEER ELECTRONICS, INC. | RN731ETTP1072B25 | 1 |  | PSRR4 |
|  | N |  | Y(5) | 73 | 61100D400-017-G |  | RES,1.87KOhm,+/-0.1%,1/16W,G,SMD0402 | KOA SPEER ELECTRONICS, INC. | RN731ETTP1871B25 | 1 | Y | PSRR10 |
|  | N | ND | Y(4) | 74 | 610109900-017-G |  | RES,1KOhm,+/-1%,1/10W,G,SMD0603 | KOA SPEER ELECTRONICS, INC. | RK73H1JTTD1001F | 1 | N | PSRR21 |
|  | ND |  | Y(5) | 75 | 61100PM00-017-G |  | RES,453 Ohm,+/-0.1%,1/16W,G,SMD0402 | KOA SPEER ELECTRONICS, INC. | RN731ETTP4530B25 | 1 |  | PSRR23 |
|  | N |  | N | 76 | 880302300-065-G |  | Converter,input 40V~60V,600W,G,Q54SJ12050NNDH | DELTA ELECTRONICS INDUSTRIAL CO.,LTD | Q54SJ12050NNDH | 1 |  | PSUU2 |
|  | ND | ND | Y(3) | 77 | 510507500-185-G |  | MOS N/P,FDC6327C,20V,2.7/1.9A,80m/170m@4.5V,G,SuperSOT-6,SMD | FAIRCHILD SEMICONDUCTOR CORP | FDC6327C | 1 |  | QN1 |
|  | ND | ND | Y(3) | 78 | 510301N00-223-G |  | MOS N,2N7002LT1G,60V,0.115A,7.5ohm@5V,G,SOT23-3,SMD | ON SEMICONDUCTOR CORP | 2N7002LT1G | 2 | N | Q3,Q4 |
|  | ND | ND | Y(4) | 79 | 61010FG00-017-G |  | RES,20KOhm,+/-5%,1/16W,G,SMD0402 | KOA SPEER ELECTRONICS, INC. | RK73B1ETTP203J | 5 | N | R60,R61,R62,R63,R64 |
|  | ND | ND | Y(4) | 80 | 61011WQ00-017-G |  | RES,3KOhm,+/-1%,1/16W,G,SMD0402 | KOA SPEER ELECTRONICS, INC. | RK73H1ETTP3001F | 2 | N | R67,R1799 |
|  | ND | ND | Y(4) | 81 | 610102C00-017-G |  | RES,15KOhm,+/-5%,1/16W,G,SMD0402 | KOA SPEER ELECTRONICS, INC. | RK73B1ETTP153J | 2 | N | R77,R1800 |
|  |  |  | Y(4) | 82 | 61010KJ00-017-G |  | RES,3.3KOhm,+/-5%,1/16W,G,SMD0402 | KOA SPEER ELECTRONICS, INC. | RK73B1ETTP332J | 23 | N | R90,R443,R470,R1030,R1036,R1037,R1038,R1039,R1040,R1045,R1046,R1049,R1052,R1053,R1056,R1057,R1058,R1061,R1062,R1065,R1066,R1231,R1338 |
|  | N | ND | Y(4) | 83 | 610102700-017-G |  | RES,49.9 Ohm,+/-1%,1/16W,G,SMD0402 | KOA SPEER ELECTRONICS, INC. | RK73H1ETTP49R9F | 127 | N | R91,R92,R93,R102,R114,R115,R117,R118,R119,R120,R121,R134,R135,R136,R144,R145,R149,R156,R157,R159,R165,R168,R170,R176,R178,R181,R185,R190,R191,R199,R201,R202,R210,R211,R212,R218,R219,R220,R228,R229,R233,R241,R242,R243,R249,R252,R254,R260,R262,R265,R269,R274,R275,R283,R285,R286,R294,R295,R296,R444,R450,R451,R462,R489,R490,R491,R499,R500,R504,R511,R512,R514,R520,R523,R525,R532,R534,R536,R540,R545,R546,R554,R556,R557,R565,R566,R567,R573,R574,R575,R583,R584,R588,R595,R596,R598,R604,R607,R609,R616,R618,R619,R624,R629,R630,R638,R640,R641,R649,R650,R651,R1140,R1279,R1399,R1400,R1403,R1404,R1405,R1791,R1792,R1793,R1794,R1795,R1796,R1811,R1830,R1831 |
|  |  |  | Y(4) | 84 | 610112W00-017-G |  | RES,2KOhm,+/-5%,1/16W,G,SMD0402 | KOA SPEER ELECTRONICS, INC. | RK73B1ETTP202J | 2 | N | R96,R448 |
|  | N | other | Y(4) | 85 | 610107C00-017-G |  | RES,10KOhm,+/-5%,1/16W,G,SMD0402 | KOA SPEER ELECTRONICS, INC. | RK73B1ETTP103J | 3 | N | R116,R305,R471 |
|  | ND | ND | Y(4) | 86 | 61011KS00-017-G |  | RES,47KOhm,+/-1%,1/16W,G,SMD0402 | KOA SPEER ELECTRONICS, INC. | RK73H1ETTP4702F | 3 | N | R652,R658,R720 |
|  | N | other | Y(4) | 87 | 61010FL00-017-G |  | RES,2.2KOhm,+/-5%,1/16W,G,SMD0402 | KOA SPEER ELECTRONICS, INC. | RK73B1ETTP222J | 20 | N | R664,R665,R666,R667,R672,R673,R675,R676,R691,R692,R693,R694,R695,R696,R697,R698,R716,R718,R1020,R1021 |
|  | N | ND | Y(4) | 88 | 610112J00-017-G |  | RES,200 Ohm,+/-1%,1/16W,G,SMD0402 | KOA SPEER ELECTRONICS, INC. | RK73H1ETTP2000F | 5 | N | R680,R688,R689,R746,R771 |
|  | ND | ND | Y(4) | 89 | 610112L00-017-G |  | RES,1.24KOhm,+/-1%,1/16W,G,SMD0402 | KOA SPEER ELECTRONICS, INC. | RK73H1ETTP1241F | 1 | N | R690 |
|  | ND | ND | Y(4) | 90 | 610104E00-017-G |  | RES,470 Ohm,+/-1%,1/10W,G,SMD0603 | KOA SPEER ELECTRONICS, INC. | RK73H1JTTD4700F | 1 | N | R699 |
|  | N | ND | Y(4) | 91 | 61010DL01-017-G |  | RES,0 Ohm,+/-5%,1/8W,G,SMD0805 | KOA SPEER ELECTRONICS, INC. | RK73Z2ATTD | 2 | N | R700,R701 |
|  | N | ND | Y(4) | 92 | 61013W100-017-G |  | RES,20mOhm,+/-1%,1/5W,G,SMD0603 | KOA SPEER ELECTRONICS, INC. | UR73D1JTTD20L0F | 1 |  | R702 |
|  | N | other | Y(4) | 93 | 610100T00-017-G |  | RES,1KOhm,+/-5%,1/16W,G,SMD0402 | KOA SPEER ELECTRONICS, INC. | RK73B1ETTP102J | 13 | N | R703,R704,R705,R706,R707,R711,R712,R713,R714,R715,R735,R736,R737 |
|  | ND | ND | Y(4) | 94 | 61011H500-017-G |  | RES,22 Ohm,+/-1%,1/16W,G,SMD0402 | KOA SPEER ELECTRONICS, INC. | RK73H1ETTP22R0F | 6 | N | R721,R725,R727,R729,R730,R1012 |
|  | ND | ND | Y(4) | 95 | 610112B00-017-G |  | RES,3.4KOhm,+/-1%,1/16W,G,SMD0402 | KOA SPEER ELECTRONICS, INC. | RK73H1ETTP3401F | 2 | N | R733,R734 |
|  | ND |  | Y(4) | 96 | 61011U901-017-G |  | RES,120Ohm,+/-1%,1/20W,G,SMD0201 | KOA SPEER ELECTRONICS, INC. | RK73H1HTTC1200F | 4 |  | R837,R838,R863,R892 |
|  | N | ND | Y(4) | 97 | 61010FF00-017-G |  | RES,150 Ohm,+/-1%,1/16W,G,SMD0402 | KOA SPEER ELECTRONICS, INC. | RK73H1ETTP1500F | 6 | N | R1006,R1007,R1008,R1009,R1010,R1011 |
|  | N | ND | Y(4) | 98 | 61011DR00-017-G |  | RES,2.2KOhm,+/-1%,1/16W,G,SMD0402 | KOA SPEER ELECTRONICS, INC. | RK73H1ETTP2201F | 2 | N | R1018,R1024 |
|  | N | ND | Y(4) | 99 | 610115J00-017-G |  | RES,33 Ohm,+/-1%,1/16W,G,SMD0402 | KOA SPEER ELECTRONICS, INC. | RK73H1ETTP33R0F | 2 | N | R1019,R1025 |
|  | N | other | Y(4) | 100 | 610107F00-017-G |  | RES,1KOhm,+/-5%,1/10W,G,SMD0603 | KOA SPEER ELECTRONICS, INC. | RK73B1JTTD102J | 3 | N | R1079,R1081,R1778 |
|  | N | ND | Y(5) | 101 | 611003D00-017-G |  | RES,1KOhm,+/-0.1%,1/16W,G,SMD0402 | KOA SPEER ELECTRONICS, INC. | RN731ETTP1001B25 | 1 | Y | R1112 |
|  | N |  | Y(5) | 102 | 61100QH00-017-G |  | RES,510 Ohm,+/-0.1%,1/16W,G,SMD0402 | KOA SPEER ELECTRONICS, INC. | RN731ETTP5100B25 | 1 | Y | R1113 |
|  | ND | ND | Y(4) | 103 | 61011CY00-017-G |  | RES,5.6KOhm,+/-1%,1/16W,G,SMD0402 | KOA SPEER ELECTRONICS, INC. | RK73H1ETTP5601F | 4 | N | R1266,R1270,R1274,R1278 |
|  | ND | ND | Y(5) | 104 | 61100AH00-017-G |  | RES,10KOhm,+/-0.5%,1/16W,G,SMD0402 | KOA SPEER ELECTRONICS, INC. | RN731ETTP1002D25 | 6 | Y | R1299,R1300,R1301,R1302,R1306,R1309 |
|  | N |  | Y(4) | 105 | 610154700-017-G |  | RES,10KOhm,+/-5%,1/8W,G,SMD0402 | KOA SPEER ELECTRONICS, INC. | SG73P1ETTP103J | 2 |  | R1324,R1326 |
|  | ND | ND | Y(4) | 106 | 61012LR00-017-G |  | RES,1KOhm,+/-0.5%,1/16W,G,SMD0402 | KOA SPEER ELECTRONICS, INC. | RK73H1ETTP1001D | 1 | N | R1481 |
|  | ND | ND | Y(4) | 107 | 610124C00-017-G |  | RES,57.6 Ohm,+/-1%,1/16W,G,SMD0402 | KOA SPEER ELECTRONICS, INC. | RK73H1ETTP57R6F | 4 | N | R1836,R1838,R1839,R1846 |
|  | Y | ND | N | 108 | 41050W700-46Y-G |  | Flash,AT45DB081E-SHNHC-T,1.65~3.6V,8M,SPI,G,SOIC-8,SMD | Adesto Technologies Corporation | AT45DB081E-SHNHC-T | 1 |  | U_LOM1_ROM1 |
|  | N | other | Y(1) | 109 | 320403K00-183-G |  | IC,Temp Sensor,TMP75AIDR,3°C,G,SOIC-8,SMD | TEXAS INSTRUMENTS | TMP75AIDR | 1 | N | U_TMP |
|  | ND |  | N | 110 | 310406Q00-031-G |  | IC,Multiplexer,CBTL01023GM,3V~3.6V,G,XQFN-10,SMD | NXP SEMICONDUCTORS | CBTL01023GM | 1 |  | U12 |
|  | ND |  | N | 111 | 410512F00-233-G |  | Flash,MX66L51235FMI-10G,2.7V~3.6V,512M,SPI,G,SOP-16,SMD | MACRONIX INTERNATIONAL CO.,LTD. | MX66L51235FMI-10G | 2 |  | U20,U21 |
|  | ND | ND | Y(2) | 112 | 310504D00-031-G |  | IC,Buffer,74LVC2G125DP,1.65~5.5V,G,TSSOP-8,SMD | NXP SEMICONDUCTORS | 74LVC2G125DP | 1 | N | U31 |
|  | ND | ND | Y(1) | 113 | 410400T00-214-G |  | EEPROM,M93C46-WMN6TP,2.5~5.5V,1K,3-wire serial,G,SO-8,SMD | ST MICRO ELECTRONICS,INC | M93C46-WMN6TP | 1 | N | U39 |
|  | ND | ND | Y(3) | 114 | 310502800-031-G |  | IC,Buffer,74LVC1G07GW,1.65~5.5V,G,SOT353-5,SMD | NXP SEMICONDUCTORS | 74LVC1G07GW | 1 | N | U103 |
|  | ND |  | N | 115 | 32050Q900-031-G |  | IC,LED Driver,PCA9551PW,G,TSSOP-16,SMD | NXP SEMICONDUCTORS | PCA9551PW | 1 |  | U172 |
|  | N | Other | Y(4) | 116 | 310203U00-223-G |  | IC,Trigger,NL17SZ14DFT2G,1.65~5.5V,G,SOT353-5,SMD | ON SEMICONDUCTOR CORP | NL17SZ14DFT2G | 1 | N | U173 |
|  | ND |  | N | 117 | 71011RD00-100-G |  | XTAL,25MHz,+/-25ppm,20pF,G,SMD | TXC CORPORATION | 7V25000016 | 1 |  | X1 |
|  | ND | ND | N | 118 | 34062MW00-309-G |  | CONN,Header,WTB,2X5,V/T,Bla,1.27mm,10u,G,SMD-10 | SAMTEC INC. | FTSH-105-01-L-DV-K-P-TR | 1 |  | J_JTAG_LOM1 |
|  | ND |  | N | 119 | 3406AQH00-317-G |  | CONN,Header,Pin Header,1X6,V/T,Bla,2.54mm,G,SMD-6 | MOLEX INCORPORATED | 87898-0656 | 1 |  | J_UART_LOM1 |
|  | ND |  | N | 120 | 3406AGV00-317-G |  | CONN,Header,WTB,2X8,V/T,Whi,1.25mm,G,SMD-16 | MOLEX INCORPORATED | 5054331671 | 1 |  | J12 |
|  | ND |  | N | 121 | 34131WT00-G78-G |  | CONN,BTB,Bla,0.8mm,7.87u,G,SMD-80 | FCI CONNECTORS HONGKONG LTD. | 10139781-082402LF | 1 |  | J18 |
|  | ND | ND | N | 122 | 3406A9H00-309-G |  | CONN,Header,Socket,V/T,Bla,2.54mm,30u,G,SMD-12 | SAMTEC INC. | SSM-106-S-DV-P-TR | 1 |  | J34 |
|  | ND |  | N | 123 | 340653G00-317-G |  | CONN,Header,Shrouded,2X11,V/T,Bla,2mm,30u,G,SMD-22 | MOLEX INCORPORATED | 87832-6023 | 1 |  | J102 |
|  | ND |  | N | 124 | 3406ALY00-317-G |  | CONN,Header,Shrouded,2X6,V/T,Bla,2mm,30u,G,SMD-12 | MOLEX INCORPORATED | 87832-5523 | 1 |  | J103 |
|  | ND |  | N | 125 | 34060VU00-309-G |  | CONN,Pin Header,1X2,V/T,Bla,2.54mm,10u,G,SMD-2 | SAMTEC INC. | TSM-102-01-L-SV-P-TR | 38 |  | J104,J105,J106,J107,J108,J109,J110,J111,J112,J113,J114,J115,J116,J117,J118,J119,J120,J121,J122,J123,J124,J125,J126,J127,J128,J129,J130,J131,J132,J133,J134,J135,J136,J137,J138,J139,J140,J141 |
